# BASEBOARD_FAB2 (Tioga Pass) — schematic netlist excerpt (pin names and nets, part order shuffled) for the footprints in the layout excerpt that follows; sources: Cadence DE-HDL packaged netlist, KiCad conversion of Wiwynn_Tioga_Pass_MB.brd

C2P15  CAP_A  0.1UF 16V 10% X7R  pkg 0402V  page 188 : A = P12V_STBY ; B = GND
C2U28  CAP_A  0.1UF 16V 10% X7R  pkg 0402V  page 161 : A = P3V3_STBY ; B = GND
R7E20  RES  1.00K 1% CHIP  pkg 0402  page 192 : A = FM_MEM_EVENT_FUNC ; B = GND

(kicad_pcb
	(version 20260206)
	(generator "pcbnew")
	(generator_version "10.0")
	(general
		(thickness 1.6)
		(legacy_teardrops no)
	)
	(paper "A4")
	(title_block
		(title "Wiwynn_Tioga_Pass_MB.brd")
		(comment 1 "Tioga Pass / footprints 3423-3425 of 4770")
	)
	(layers
		(0 "F.Cu" signal "TOP")
		(4 "In1.Cu" signal "L2GND")
		(6 "In2.Cu" signal "L3")
		(8 "In3.Cu" signal "L4GND")
		(10 "In4.Cu" signal "L5")
		(12 "In5.Cu" signal "L6GND")
		(14 "In6.Cu" signal "L7VCC")
		(16 "In7.Cu" signal "L8VCC")
		(18 "In8.Cu" signal "L9GND")
		(20 "In9.Cu" signal "L10")
		(22 "In10.Cu" signal "L11GND")
		(24 "In11.Cu" signal "L12")
		(26 "In12.Cu" signal "L13GND")
		(2 "B.Cu" signal "BOTTOM")
		(9 "F.Adhes" user "F.Adhesive")
		(11 "B.Adhes" user "B.Adhesive")
		(13 "F.Paste" user "Package Geometry/Pastemask Top")
		(15 "B.Paste" user "Package Geometry/Pastemask Bottom")
		(5 "F.SilkS" user "Ref Des/Silkscreen Top")
		(7 "B.SilkS" user "Ref Des/Silkscreen Bottom")
		(1 "F.Mask" user "Board Geometry/Soldermask Top")
		(3 "B.Mask" user "Board Geometry/Soldermask Bottom")
		(17 "Dwgs.User" user "User.Drawings")
		(19 "Cmts.User" user "User.Comments")
		(21 "Eco1.User" user "User.Eco1")
		(23 "Eco2.User" user "User.Eco2")
		(25 "Edge.Cuts" user "Board Geometry/Outline")
		(27 "Margin" user)
		(31 "F.CrtYd" user "Package Geometry/Place Bound Top")
		(29 "B.CrtYd" user "Package Geometry/Place Bound Bottom")
		(35 "F.Fab" user "Ref Des/Assembly Top")
		(33 "B.Fab" user "Ref Des/Assembly Bottom")
	)
	(footprint ""
		(layer "B.Cu")
		(at 403.8854 2.4384 -90)
		(property "Reference" "C2U28"
			(at 0 0 90)
			(layer "B.SilkS")
			(hide yes)
			(effects
				(font
					(size 1.27 1.27)
				)
				(justify mirror)
			)
		)
		(property "Value" ""
			(at 0 0 90)
			(layer "B.Fab")
			(effects
				(font
					(size 1.27 1.27)
				)
				(justify mirror)
			)
		)
		(duplicate_pad_numbers_are_jumpers no)
		(fp_poly
			(pts
				(xy -0.3048 -0.1016) (xy -0.3048 0.9906) (xy 0.3048 0.9906) (xy 0.3048 -0.1016)
			)
			(stroke
				(width 0)
				(type default)
			)
			(fill no)
			(layer "B.CrtYd")
		)
		(fp_line
			(start -0.3048 0.9906)
			(end -0.3048 -0.1016)
			(stroke
				(width 0.1)
				(type default)
			)
			(layer "B.Fab")
		)
		(fp_line
			(start 0.3048 0.9906)
			(end -0.3048 0.9906)
			(stroke
				(width 0.1)
				(type default)
			)
			(layer "B.Fab")
		)
		(fp_line
			(start -0.3048 -0.1016)
			(end 0.3048 -0.1016)
			(stroke
				(width 0.1)
				(type default)
			)
			(layer "B.Fab")
		)
		(fp_line
			(start 0.3048 -0.1016)
			(end 0.3048 0.9906)
			(stroke
				(width 0.1)
				(type default)
			)
			(layer "B.Fab")
		)
		(pad "1" smd rect
			(at 0 0 90)
			(size 0.508 0.508)
			(layers "B.Cu" "B.Mask" "B.Paste")
			(net "P3V3_STBY")
		)
		(pad "2" smd rect
			(at 0 0.889 90)
			(size 0.508 0.508)
			(layers "B.Cu" "B.Mask" "B.Paste")
			(net "GND")
		)
		(zone
			(layer "B.Cu")
			(hatch none 0.5)
			(connect_pads
				(clearance 0)
			)
			(min_thickness 0.25)
			(keepout
				(tracks not_allowed)
				(vias allowed)
				(pads allowed)
				(copperpour not_allowed)
				(footprints allowed)
			)
			(placement
				(enabled no)
				(sheetname "")
			)
			(fill
				(thermal_gap 0.5)
				(thermal_bridge_width 0.5)
				(island_removal_mode 0)
			)
			(polygon
				(pts
					(xy 403.2504 2.6924) (xy 403.2504 2.1844) (xy 403.6314 2.1844) (xy 403.6314 2.6924)
				)
			)
		)
		(zone
			(layer "B.Cu")
			(hatch none 0.5)
			(connect_pads
				(clearance 0)
			)
			(min_thickness 0.25)
			(keepout
				(tracks allowed)
				(vias not_allowed)
				(pads allowed)
				(copperpour not_allowed)
				(footprints allowed)
			)
			(placement
				(enabled no)
				(sheetname "")
			)
			(fill
				(thermal_gap 0.5)
				(thermal_bridge_width 0.5)
				(island_removal_mode 0)
			)
			(polygon
				(pts
					(xy 403.6314 2.6924) (xy 403.6314 2.1844) (xy 403.2504 2.1844) (xy 403.2504 2.6924)
				)
			)
		)
	)
	(footprint ""
		(layer "B.Cu")
		(at 381.887984 -71.296276 90)
		(property "Reference" "R7E20"
			(at 0 0 90)
			(layer "B.SilkS")
			(hide yes)
			(effects
				(font
					(size 1.27 1.27)
				)
				(justify mirror)
			)
		)
		(property "Value" ""
			(at 0 0 90)
			(layer "B.Fab")
			(effects
				(font
					(size 1.27 1.27)
				)
				(justify mirror)
			)
		)
		(duplicate_pad_numbers_are_jumpers no)
		(fp_poly
			(pts
				(xy 0.2794 -0.1016) (xy -0.2794 -0.1016) (xy -0.2794 0.9906) (xy 0.2794 0.9906)
			)
			(stroke
				(width 0)
				(type default)
			)
			(fill no)
			(layer "B.CrtYd")
		)
		(fp_line
			(start 0.2794 -0.1016)
			(end 0.2794 0.9906)
			(stroke
				(width 0.1)
				(type default)
			)
			(layer "B.Fab")
		)
		(fp_line
			(start -0.2794 -0.1016)
			(end 0.2794 -0.1016)
			(stroke
				(width 0.1)
				(type default)
			)
			(layer "B.Fab")
		)
		(fp_line
			(start 0.2794 0.9906)
			(end -0.2794 0.9906)
			(stroke
				(width 0.1)
				(type default)
			)
			(layer "B.Fab")
		)
		(fp_line
			(start -0.2794 0.9906)
			(end -0.2794 -0.1016)
			(stroke
				(width 0.1)
				(type default)
			)
			(layer "B.Fab")
		)
		(pad "1" smd rect
			(at 0 0 270)
			(size 0.508 0.508)
			(layers "B.Cu" "B.Mask" "B.Paste")
			(net "FM_MEM_EVENT_FUNC")
		)
		(pad "2" smd rect
			(at 0 0.889 270)
			(size 0.508 0.508)
			(layers "B.Cu" "B.Mask" "B.Paste")
			(net "GND")
		)
		(zone
			(layer "B.Cu")
			(hatch none 0.5)
			(connect_pads
				(clearance 0)
			)
			(min_thickness 0.25)
			(keepout
				(tracks allowed)
				(vias not_allowed)
				(pads allowed)
				(copperpour not_allowed)
				(footprints allowed)
			)
			(placement
				(enabled no)
				(sheetname "")
			)
			(fill
				(thermal_gap 0.5)
				(thermal_bridge_width 0.5)
				(island_removal_mode 0)
			)
			(polygon
				(pts
					(xy 382.141984 -71.550276) (xy 382.141984 -71.042276) (xy 382.522984 -71.042276) (xy 382.522984 -71.550276)
				)
			)
		)
		(zone
			(layer "B.Cu")
			(hatch none 0.5)
			(connect_pads
				(clearance 0)
			)
			(min_thickness 0.25)
			(keepout
				(tracks not_allowed)
				(vias allowed)
				(pads allowed)
				(copperpour not_allowed)
				(footprints allowed)
			)
			(placement
				(enabled no)
				(sheetname "")
			)
			(fill
				(thermal_gap 0.5)
				(thermal_bridge_width 0.5)
				(island_removal_mode 0)
			)
			(polygon
				(pts
					(xy 382.522984 -71.550276) (xy 382.522984 -71.042276) (xy 382.141984 -71.042276) (xy 382.141984 -71.550276)
				)
			)
		)
	)
	(footprint ""
		(layer "B.Cu")
		(at 443.865 -64.7446 180)
		(property "Reference" "C2P15"
			(at 0 0 0)
			(layer "B.SilkS")
			(hide yes)
			(effects
				(font
					(size 1.27 1.27)
				)
				(justify mirror)
			)
		)
		(property "Value" ""
			(at 0 0 0)
			(layer "B.Fab")
			(effects
				(font
					(size 1.27 1.27)
				)
				(justify mirror)
			)
		)
		(duplicate_pad_numbers_are_jumpers no)
		(fp_poly
			(pts
				(xy -0.3048 -0.1016) (xy -0.3048 0.9906) (xy 0.3048 0.9906) (xy 0.3048 -0.1016)
			)
			(stroke
				(width 0)
				(type default)
			)
			(fill no)
			(layer "B.CrtYd")
		)
		(fp_line
			(start 0.3048 0.9906)
			(end -0.3048 0.9906)
			(stroke
				(width 0.1)
				(type default)
			)
			(layer "B.Fab")
		)
		(fp_line
			(start 0.3048 -0.1016)
			(end 0.3048 0.9906)
			(stroke
				(width 0.1)
				(type default)
			)
			(layer "B.Fab")
		)
		(fp_line
			(start -0.3048 0.9906)
			(end -0.3048 -0.1016)
			(stroke
				(width 0.1)
				(type default)
			)
			(layer "B.Fab")
		)
		(fp_line
			(start -0.3048 -0.1016)
			(end 0.3048 -0.1016)
			(stroke
				(width 0.1)
				(type default)
			)
			(layer "B.Fab")
		)
		(pad "1" smd rect
			(at 0 0)
			(size 0.508 0.508)
			(layers "B.Cu" "B.Mask" "B.Paste")
			(net "P12V_STBY")
		)
		(pad "2" smd rect
			(at 0 0.889)
			(size 0.508 0.508)
			(layers "B.Cu" "B.Mask" "B.Paste")
			(net "GND")
		)
		(zone
			(layer "B.Cu")
			(hatch none 0.5)
			(connect_pads
				(clearance 0)
			)
			(min_thickness 0.25)
			(keepout
				(tracks not_allowed)
				(vias allowed)
				(pads allowed)
				(copperpour not_allowed)
				(footprints allowed)
			)
			(placement
				(enabled no)
				(sheetname "")
			)
			(fill
				(thermal_gap 0.5)
				(thermal_bridge_width 0.5)
				(island_removal_mode 0)
			)
			(polygon
				(pts
					(xy 443.611 -65.3796) (xy 444.119 -65.3796) (xy 444.119 -64.9986) (xy 443.611 -64.9986)
				)
			)
		)
		(zone
			(layer "B.Cu")
			(hatch none 0.5)
			(connect_pads
				(clearance 0)
			)
			(min_thickness 0.25)
			(keepout
				(tracks allowed)
				(vias not_allowed)
				(pads allowed)
				(copperpour not_allowed)
				(footprints allowed)
			)
			(placement
				(enabled no)
				(sheetname "")
			)
			(fill
				(thermal_gap 0.5)
				(thermal_bridge_width 0.5)
				(island_removal_mode 0)
			)
			(polygon
				(pts
					(xy 443.611 -64.9986) (xy 444.119 -64.9986) (xy 444.119 -65.3796) (xy 443.611 -65.3796)
				)
			)
		)
	)
)
